FILE_TYPE = MACRO_DRAWING;
SET COLOR_WIRE YELLOW;
SET COLOR_PROP ORANGE;
SET COLOR_DOT WHITE;
SET COLOR_ARC YELLOW;
SET COLOR_BODY GREEN;
SET COLOR_NOTE PURPLE;
SET PROP_DISPLAY VALUE;
SET PAGE_NUMBER P213;
FORCEADD OFFPAGE..1
(-9250 4950);
FORCEPROP 2 LAST $XR1 260 
J 0
(-9622 4950);
DISPLAY 0.638298 (-9622 4950);
PAINT MONO (-9622 4950);
FORCEPROP 2 LAST $XR0 214 
J 0
(-9502 4950);
DISPLAY 0.638298 (-9502 4950);
PAINT MONO (-9502 4950);
FORCEPROP 1 LAST OFFPAGE TRUE
J 0
(-8925 4825);
DISPLAY 0.872340 (-8925 4825);
PAINT GREEN (-8925 4825);
DISPLAY INVISIBLE (-8925 4825);
FORCEPROP 1 LAST COMMENT_BODY TRUE
J 0
(-9125 4850);
DISPLAY 0.872340 (-9125 4850);
PAINT GREEN (-9125 4850);
DISPLAY INVISIBLE (-9125 4850);
FORCEPROP 2 LAST PATH I1
J 0
(-9500 5000);
DISPLAY 1.021277 (-9500 5000);
DISPLAY INVISIBLE (-9500 5000);
FORCEPROP 2 LAST CDS_LIB standard
J 0
(-9250 4950);
DISPLAY INVISIBLE (-9250 4950);
FORCEADD OFFPAGE..2
(-5725 4950);
FORCEPROP 2 LAST $XR0 191 
J 0
(-5536 4950);
DISPLAY 0.638298 (-5536 4950);
PAINT MONO (-5536 4950);
FORCEPROP 2 LAST PATH I10
J 0
(-5175 5000);
DISPLAY 1.021277 (-5175 5000);
DISPLAY INVISIBLE (-5175 5000);
FORCEPROP 1 LAST OFFPAGE TRUE
J 0
(-5400 4825);
DISPLAY 0.872340 (-5400 4825);
DISPLAY INVISIBLE (-5400 4825);
FORCEPROP 1 LAST COMMENT_BODY TRUE
J 0
(-5770 4855);
DISPLAY 0.872340 (-5770 4855);
PAINT GREEN (-5770 4855);
DISPLAY INVISIBLE (-5770 4855);
FORCEPROP 2 LAST CDS_LIB standard
J 0
(-5725 4950);
DISPLAY INVISIBLE (-5725 4950);
FORCEADD OFFPAGE..4
R 2
(-9500 2300);
FORCEPROP 2 LAST $XR1 252 
J 0
(-9872 2300);
DISPLAY 0.638298 (-9872 2300);
PAINT MONO (-9872 2300);
FORCEPROP 2 LAST $XR0 214 
J 0
(-9752 2300);
DISPLAY 0.638298 (-9752 2300);
PAINT MONO (-9752 2300);
FORCEPROP 1 LAST OFFPAGE TRUE
J 2
(-9825 2175);
DISPLAY 0.872340 (-9825 2175);
PAINT GREEN (-9825 2175);
DISPLAY INVISIBLE (-9825 2175);
FORCEPROP 1 LAST COMMENT_BODY TRUE
J 2
(-9475 2200);
DISPLAY 0.872340 (-9475 2200);
PAINT GREEN (-9475 2200);
DISPLAY INVISIBLE (-9475 2200);
FORCEPROP 2 LAST CDS_LIB standard
J 0
(-9500 2300);
DISPLAY INVISIBLE (-9500 2300);
FORCEPROP 2 LAST PATH I12
J 0
(-9750 2350);
DISPLAY 1.021277 (-9750 2350);
DISPLAY INVISIBLE (-9750 2350);
FORCEADD UNIVERSAL_GND..1
(-8275 1975);
FORCEPROP 3 LASTPIN (-8275 2025) SIG_NAME GND\g
J 0
(-8265 2035);
DISPLAY 0.659574 (-8265 2035);
PAINT MONO (-8265 2035);
DISPLAY INVISIBLE (-8265 2035);
FORCEPROP 1 LAST PATH I17
J 0
(-8200 1975);
DISPLAY 0.872340 (-8200 1975);
PAINT AQUA (-8200 1975);
DISPLAY INVISIBLE (-8200 1975);
FORCEPROP 2 LAST CDS_LIB logical_power
J 0
(-8275 1975);
DISPLAY INVISIBLE (-8275 1975);
FORCEPROP 1 LAST HDL_POWER GND
J 1
(-8250 1900);
DISPLAY 0.872340 (-8250 1900);
PAINT GREEN (-8250 1900);
DISPLAY INVISIBLE (-8250 1900);
FORCEADD Q_RES..2
(-8275 2950);
FORCEPROP 1 LAST PART_NUMBER CS24702JB10
J 0
(-8235 2775);
DISPLAY 0.638298 (-8235 2775);
DISPLAY INVISIBLE (-8235 2775);
FORCEPROP 1 LAST PACK_TYPE 0402LF
J 0
(-8235 2825);
DISPLAY 0.638298 (-8235 2825);
FORCEPROP 1 LAST TOLERANCE 5%
J 0
(-8230 2975);
DISPLAY 0.638298 (-8230 2975);
FORCEPROP 1 LAST WATTAGE 1/16W
J 0
(-8235 2925);
DISPLAY 0.638298 (-8235 2925);
FORCEPROP 1 LAST VALUE 4.7K
J 0
(-8230 3025);
DISPLAY 0.638298 (-8230 3025);
FORCEPROP 1 LAST MATERIAL CHIP
J 0
(-8235 2875);
DISPLAY 0.638298 (-8235 2875);
FORCEPROP 1 LAST $LOCATION R4604
J 0
(-8230 3075);
DISPLAY 0.638298 (-8230 3075);
FORCEPROP 1 LASTPIN (-8275 3050) $PN 1
J 0
(-8270 3012);
DISPLAY 0.787234 (-8270 3012);
FORCEPROP 1 LASTPIN (-8275 2850) $PN 2
J 0
(-8270 2860);
DISPLAY 0.787234 (-8270 2860);
FORCEPROP 1 LAST PATH I18
J 0
(-8225 3125);
DISPLAY 0.978723 (-8225 3125);
PAINT WHITE (-8225 3125);
DISPLAY INVISIBLE (-8225 3125);
FORCEPROP 2 LAST CDS_LIB pure_quanta
J 0
(-8275 2950);
PAINT MONO (-8275 2950);
DISPLAY INVISIBLE (-8275 2950);
FORCEPROP 2 LAST CDS_LOCATION R4604
J 0
(-8225 3175);
DISPLAY 1.021277 (-8225 3175);
DISPLAY INVISIBLE (-8225 3175);
FORCEPROP 2 LAST $SEC 1
J 0
(-8225 3175);
DISPLAY 0.680851 (-8225 3175);
PAINT MONO (-8225 3175);
DISPLAY INVISIBLE (-8225 3175);
FORCEPROP 2 LAST CDS_SEC 1
J 0
(-8225 3175);
DISPLAY 1.021277 (-8225 3175);
DISPLAY INVISIBLE (-8225 3175);
FORCEADD UNIVERSAL_POWER..1
(-8275 3175);
FORCEPROP 3 LASTPIN (-8275 3125) SIG_NAME P3V3_AUX\g
J 0
(-8265 3135);
DISPLAY 0.659574 (-8265 3135);
PAINT MONO (-8265 3135);
DISPLAY INVISIBLE (-8265 3135);
FORCEPROP 1 LAST HDL_POWER P3V3_AUX
J 1
(-8275 3225);
DISPLAY 0.872340 (-8275 3225);
PAINT GREEN (-8275 3225);
FORCEPROP 1 LAST PATH I19
J 0
(-8225 3200);
DISPLAY 0.872340 (-8225 3200);
PAINT AQUA (-8225 3200);
DISPLAY INVISIBLE (-8225 3200);
FORCEPROP 2 LAST CDS_LIB logical_power
J 0
(-8275 3175);
PAINT MONO (-8275 3175);
DISPLAY INVISIBLE (-8275 3175);
FORCEADD 74LVC2G17GW..1
(-8000 4825);
FORCEPROP 1 LAST PART_NUMBER AL2G0017005
J 0
(-7773 4515);
DISPLAY 0.723404 (-7773 4515);
PAINT GREEN (-7773 4515);
DISPLAY INVISIBLE (-7773 4515);
FORCEPROP 1 LAST MATERIAL IC
J 0
(-7773 4430);
DISPLAY 0.723404 (-7773 4430);
PAINT GREEN (-7773 4430);
FORCEPROP 2 LAST VALUE 74LVC2G17GW
J 0
(-8350 5125);
DISPLAY 0.638298 (-8350 5125);
FORCEPROP 2 LAST PART_TYPE SMLF
J 0
(-8150 5175);
DISPLAY 0.638298 (-8150 5175);
FORCEPROP 1 LAST $LOCATION U150
J 0
(-7773 4585);
DISPLAY 0.723404 (-7773 4585);
PAINT GREEN (-7773 4585);
FORCEPROP 0 LASTPIN (-8375 4950) $PN 1
J 2
(-8385 4960);
DISPLAY 0.680851 (-8385 4960);
PAINT MONO (-8385 4960);
FORCEPROP 0 LASTPIN (-8375 4700) $PN 3
J 2
(-8385 4710);
DISPLAY 0.680851 (-8385 4710);
PAINT MONO (-8385 4710);
FORCEPROP 0 LASTPIN (-7625 4950) $PN 6
J 0
(-7615 4960);
DISPLAY 0.680851 (-7615 4960);
PAINT MONO (-7615 4960);
FORCEPROP 0 LASTPIN (-7625 4700) $PN 4
J 0
(-7615 4710);
DISPLAY 0.680851 (-7615 4710);
PAINT MONO (-7615 4710);
FORCEPROP 0 LASTPIN (-7975 4400) $PN 2
R 1
J 2
(-7965 4390);
DISPLAY 0.680851 (-7965 4390);
PAINT MONO (-7965 4390);
FORCEPROP 0 LASTPIN (-7975 5250) $PN 5
R 1
J 0
(-7965 5260);
DISPLAY 0.680851 (-7965 5260);
PAINT MONO (-7965 5260);
FORCEPROP 2 LAST CDS_LIB pure_quanta
J 0
(-8000 4825);
DISPLAY INVISIBLE (-8000 4825);
FORCEPROP 1 LAST CDS_LMAN_SYM_OUTLINE -225,275,225,-275
J 0
(-8000 4825);
DISPLAY 0.468085 (-8000 4825);
PAINT GREEN (-8000 4825);
DISPLAY INVISIBLE (-8000 4825);
FORCEPROP 1 LAST NEEDS_NO_SIZE TRUE
J 0
(-7775 4824);
DISPLAY 0.468085 (-7775 4824);
PAINT GREEN (-7775 4824);
DISPLAY INVISIBLE (-7775 4824);
FORCEPROP 1 LAST PATH I2
J 0
(-7775 4550);
DISPLAY 0.723404 (-7775 4550);
PAINT GREEN (-7775 4550);
DISPLAY INVISIBLE (-7775 4550);
FORCEPROP 0 LAST CDS_LOCATION U150
J 0
(-8125 5275);
DISPLAY 1.021277 (-8125 5275);
DISPLAY INVISIBLE (-8125 5275);
FORCEPROP 0 LAST $SEC 1
J 2
(-8150 5225);
DISPLAY 0.680851 (-8150 5225);
PAINT MONO (-8150 5225);
DISPLAY INVISIBLE (-8150 5225);
FORCEPROP 0 LAST CDS_SEC 1
J 0
(-8125 5275);
DISPLAY 1.021277 (-8125 5275);
DISPLAY INVISIBLE (-8125 5275);
FORCEADD UNIVERSAL_GND..1
(-7125 2275);
FORCEPROP 3 LASTPIN (-7125 2325) SIG_NAME GND\g
J 0
(-7115 2335);
DISPLAY 0.659574 (-7115 2335);
PAINT MONO (-7115 2335);
DISPLAY INVISIBLE (-7115 2335);
FORCEPROP 1 LAST HDL_POWER GND
J 1
(-7100 2200);
DISPLAY 0.872340 (-7100 2200);
PAINT GREEN (-7100 2200);
DISPLAY INVISIBLE (-7100 2200);
FORCEPROP 2 LAST CDS_LIB logical_power
J 0
(-7125 2275);
DISPLAY INVISIBLE (-7125 2275);
FORCEPROP 1 LAST PATH I20
J 0
(-7050 2275);
DISPLAY 0.872340 (-7050 2275);
PAINT AQUA (-7050 2275);
DISPLAY INVISIBLE (-7050 2275);
FORCEADD MOSFET_NCH_DUAL..2
(-7175 2650);
FORCEPROP 1 LAST PART_NUMBER BAM138K0003
J 0
(-7024 2556);
DISPLAY 0.723404 (-7024 2556);
PAINT GREEN (-7024 2556);
DISPLAY INVISIBLE (-7024 2556);
FORCEPROP 2 LAST PART_TYPE SMLF
J 0
(-7000 2725);
DISPLAY 1.021277 (-7000 2725);
FORCEPROP 1 LAST MATERIAL IC
J 0
(-7024 2501);
DISPLAY 0.723404 (-7024 2501);
PAINT GREEN (-7024 2501);
FORCEPROP 2 LAST VALUE PJT138K
J 0
(-7000 2675);
DISPLAY 1.021277 (-7000 2675);
FORCEPROP 1 LAST $LOCATION Q144
J 0
(-7024 2626);
DISPLAY 0.723404 (-7024 2626);
PAINT GREEN (-7024 2626);
FORCEPROP 0 LASTPIN (-7125 2850) $PN 3
R 1
J 0
(-7135 2860);
DISPLAY 0.680851 (-7135 2860);
PAINT MONO (-7135 2860);
FORCEPROP 0 LASTPIN (-7375 2600) $PN 5
J 2
(-7385 2610);
DISPLAY 0.680851 (-7385 2610);
PAINT MONO (-7385 2610);
FORCEPROP 0 LASTPIN (-7125 2450) $PN 4
R 1
J 2
(-7135 2440);
DISPLAY 0.680851 (-7135 2440);
PAINT MONO (-7135 2440);
FORCEPROP 2 LAST CDS_LIB pure_quanta
J 0
(-7175 2650);
DISPLAY INVISIBLE (-7175 2650);
FORCEPROP 1 LAST NEEDS_NO_SIZE TRUE
J 0
(-7025 2541);
DISPLAY 0.468085 (-7025 2541);
PAINT GREEN (-7025 2541);
DISPLAY INVISIBLE (-7025 2541);
FORCEPROP 1 LAST CDS_LMAN_SYM_OUTLINE -150,150,150,-150
J 0
(-7175 2650);
DISPLAY 0.468085 (-7175 2650);
PAINT GREEN (-7175 2650);
DISPLAY INVISIBLE (-7175 2650);
FORCEPROP 1 LAST PATH I21
J 0
(-7025 2500);
DISPLAY 0.723404 (-7025 2500);
PAINT GREEN (-7025 2500);
DISPLAY INVISIBLE (-7025 2500);
FORCEPROP 0 LAST CDS_LOCATION Q144
J 0
(-7000 2775);
DISPLAY 1.021277 (-7000 2775);
DISPLAY INVISIBLE (-7000 2775);
FORCEPROP 0 LAST $SEC 2
J 0
(-7000 2775);
DISPLAY 0.680851 (-7000 2775);
PAINT MONO (-7000 2775);
DISPLAY INVISIBLE (-7000 2775);
FORCEPROP 0 LAST CDS_SEC 2
J 0
(-7000 2775);
DISPLAY 1.021277 (-7000 2775);
DISPLAY INVISIBLE (-7000 2775);
FORCEADD Q_RES..2
(-7125 3075);
FORCEPROP 1 LAST PART_NUMBER CS24702JB10
J 0
(-7085 2900);
DISPLAY 0.638298 (-7085 2900);
DISPLAY INVISIBLE (-7085 2900);
FORCEPROP 1 LAST MATERIAL CHIP
J 0
(-7085 3000);
DISPLAY 0.638298 (-7085 3000);
FORCEPROP 1 LAST PACK_TYPE 0402LF
J 0
(-7085 2950);
DISPLAY 0.638298 (-7085 2950);
FORCEPROP 1 LAST WATTAGE 1/16W
J 0
(-7085 3050);
DISPLAY 0.638298 (-7085 3050);
FORCEPROP 1 LAST TOLERANCE 5%
J 0
(-7080 3100);
DISPLAY 0.638298 (-7080 3100);
FORCEPROP 1 LAST VALUE 4.7K
J 0
(-7080 3150);
DISPLAY 0.638298 (-7080 3150);
FORCEPROP 1 LAST $LOCATION R4605
J 0
(-7080 3200);
DISPLAY 0.638298 (-7080 3200);
FORCEPROP 1 LASTPIN (-7125 3175) $PN 1
J 0
(-7120 3137);
DISPLAY 0.787234 (-7120 3137);
FORCEPROP 1 LASTPIN (-7125 2975) $PN 2
J 0
(-7120 2985);
DISPLAY 0.787234 (-7120 2985);
FORCEPROP 1 LAST PATH I22
J 0
(-7075 3250);
DISPLAY 0.978723 (-7075 3250);
PAINT WHITE (-7075 3250);
DISPLAY INVISIBLE (-7075 3250);
FORCEPROP 2 LAST CDS_LIB pure_quanta
J 0
(-7125 3075);
PAINT MONO (-7125 3075);
DISPLAY INVISIBLE (-7125 3075);
FORCEPROP 2 LAST CDS_LOCATION R4605
J 0
(-7075 3300);
DISPLAY 1.021277 (-7075 3300);
DISPLAY INVISIBLE (-7075 3300);
FORCEPROP 2 LAST $SEC 1
J 0
(-7075 3300);
DISPLAY 0.680851 (-7075 3300);
PAINT MONO (-7075 3300);
DISPLAY INVISIBLE (-7075 3300);
FORCEPROP 2 LAST CDS_SEC 1
J 0
(-7075 3300);
DISPLAY 1.021277 (-7075 3300);
DISPLAY INVISIBLE (-7075 3300);
FORCEADD UNIVERSAL_POWER..1
(-7125 3300);
FORCEPROP 3 LASTPIN (-7125 3250) SIG_NAME P3V3_AUX\g
J 0
(-7115 3260);
DISPLAY 0.659574 (-7115 3260);
PAINT MONO (-7115 3260);
DISPLAY INVISIBLE (-7115 3260);
FORCEPROP 1 LAST HDL_POWER P3V3_AUX
J 1
(-7125 3350);
DISPLAY 0.872340 (-7125 3350);
PAINT GREEN (-7125 3350);
FORCEPROP 1 LAST PATH I23
J 0
(-7075 3325);
DISPLAY 0.872340 (-7075 3325);
PAINT AQUA (-7075 3325);
DISPLAY INVISIBLE (-7075 3325);
FORCEPROP 2 LAST CDS_LIB logical_power
J 0
(-7125 3300);
PAINT MONO (-7125 3300);
DISPLAY INVISIBLE (-7125 3300);
FORCEADD MOSFET_NCH_DUAL..1
(-8325 2350);
FORCEPROP 1 LAST PART_NUMBER BAM138K0003
J 0
(-8174 2264);
DISPLAY 0.723404 (-8174 2264);
PAINT GREEN (-8174 2264);
DISPLAY INVISIBLE (-8174 2264);
FORCEPROP 2 LAST PART_TYPE SMLF
J 0
(-8150 2425);
DISPLAY 1.021277 (-8150 2425);
FORCEPROP 2 LAST VALUE PJT138K
J 0
(-8150 2375);
DISPLAY 1.021277 (-8150 2375);
FORCEPROP 1 LAST MATERIAL IC
J 0
(-8174 2199);
DISPLAY 0.723404 (-8174 2199);
PAINT GREEN (-8174 2199);
FORCEPROP 1 LAST LOCATION Q144
J 0
(-8174 2324);
DISPLAY 0.723404 (-8174 2324);
PAINT GREEN (-8174 2324);
FORCEPROP 0 LASTPIN (-8275 2550) $PN 6
R 1
J 0
(-8285 2560);
DISPLAY 0.680851 (-8285 2560);
PAINT MONO (-8285 2560);
FORCEPROP 0 LASTPIN (-8525 2300) $PN 2
J 2
(-8535 2310);
DISPLAY 0.680851 (-8535 2310);
PAINT MONO (-8535 2310);
FORCEPROP 0 LASTPIN (-8275 2150) $PN 1
R 1
J 2
(-8285 2140);
DISPLAY 0.680851 (-8285 2140);
PAINT MONO (-8285 2140);
FORCEPROP 1 LAST PATH I27
J 0
(-8325 2350);
DISPLAY 0.723404 (-8325 2350);
PAINT GREEN (-8325 2350);
DISPLAY INVISIBLE (-8325 2350);
FORCEPROP 2 LAST CDS_LIB pure_quanta
J 0
(-8325 2350);
DISPLAY INVISIBLE (-8325 2350);
FORCEPROP 1 LAST NEEDS_NO_SIZE TRUE
J 0
(-8325 2349);
DISPLAY 0.468085 (-8325 2349);
PAINT GREEN (-8325 2349);
DISPLAY INVISIBLE (-8325 2349);
FORCEPROP 1 LAST CDS_LMAN_SYM_OUTLINE -150,150,150,-150
J 0
(-8325 2350);
DISPLAY 0.468085 (-8325 2350);
PAINT GREEN (-8325 2350);
DISPLAY INVISIBLE (-8325 2350);
FORCEPROP 0 LAST $SEC 1
J 0
(-8150 2475);
DISPLAY 0.680851 (-8150 2475);
PAINT MONO (-8150 2475);
DISPLAY INVISIBLE (-8150 2475);
FORCEPROP 2 LAST CDS_SEC 1
J 0
(-8150 2475);
DISPLAY 1.021277 (-8150 2475);
DISPLAY INVISIBLE (-8150 2475);
FORCEADD OFFPAGE..2
(-4200 2900);
FORCEPROP 2 LAST $XR0 214 
J 0
(-4011 2900);
DISPLAY 0.638298 (-4011 2900);
PAINT MONO (-4011 2900);
FORCEPROP 2 LAST PATH I28
J 0
(-4000 2950);
DISPLAY 1.021277 (-4000 2950);
DISPLAY INVISIBLE (-4000 2950);
FORCEPROP 2 LAST CDS_LIB standard
J 0
(-4200 2900);
PAINT MONO (-4200 2900);
DISPLAY INVISIBLE (-4200 2900);
FORCEPROP 1 LAST OFFPAGE TRUE
J 0
(-3875 2775);
DISPLAY 1.170213 (-3875 2775);
PAINT GREEN (-3875 2775);
DISPLAY INVISIBLE (-3875 2775);
FORCEPROP 1 LAST COMMENT_BODY TRUE
J 0
(-4245 2805);
DISPLAY 1.170213 (-4245 2805);
PAINT GREEN (-4245 2805);
DISPLAY INVISIBLE (-4245 2805);
FORCEADD Q_RES..1
(-5850 2900);
FORCEPROP 1 LAST PART_NUMBER CS03322FB03
J 0
(-5950 2975);
DISPLAY 0.510638 (-5950 2975);
DISPLAY INVISIBLE (-5950 2975);
FORCEPROP 1 LAST VALUE 33.2
J 2
(-5650 2900);
DISPLAY 0.510638 (-5650 2900);
FORCEPROP 1 LAST TOLERANCE 1%
J 0
(-5625 2900);
DISPLAY 0.510638 (-5625 2900);
FORCEPROP 1 LAST MATERIAL CHIP
J 0
(-5950 3025);
DISPLAY 0.510638 (-5950 3025);
FORCEPROP 1 LAST WATTAGE 1/16W
J 2
(-5675 3025);
DISPLAY 0.510638 (-5675 3025);
FORCEPROP 1 LAST PACK_TYPE 0402LF
J 0
(-5550 2900);
DISPLAY 0.510638 (-5550 2900);
FORCEPROP 1 LAST $LOCATION R1446
J 0
(-6100 2900);
DISPLAY 0.787234 (-6100 2900);
FORCEPROP 1 LASTPIN (-5950 2900) $PN 1
J 0
(-5938 2912);
DISPLAY 0.787234 (-5938 2912);
FORCEPROP 1 LASTPIN (-5750 2900) $PN 2
J 0
(-5788 2912);
DISPLAY 0.787234 (-5788 2912);
FORCEPROP 1 LAST PATH I29
J 0
(-5900 3050);
DISPLAY 0.978723 (-5900 3050);
PAINT WHITE (-5900 3050);
DISPLAY INVISIBLE (-5900 3050);
FORCEPROP 2 LAST CDS_LIB pure_quanta
J 0
(-5850 2900);
PAINT MONO (-5850 2900);
DISPLAY INVISIBLE (-5850 2900);
FORCEPROP 2 LAST CDS_LOCATION R1446
J 0
(-5900 3100);
DISPLAY 1.021277 (-5900 3100);
DISPLAY INVISIBLE (-5900 3100);
FORCEPROP 2 LAST $SEC 1
J 0
(-5900 3100);
DISPLAY 0.680851 (-5900 3100);
PAINT MONO (-5900 3100);
DISPLAY INVISIBLE (-5900 3100);
FORCEPROP 2 LAST CDS_SEC 1
J 0
(-5900 3100);
DISPLAY 1.021277 (-5900 3100);
DISPLAY INVISIBLE (-5900 3100);
FORCEADD UNIVERSAL_GND..1
(-7975 4250);
FORCEPROP 3 LASTPIN (-7975 4300) SIG_NAME GND\g
J 0
(-7965 4310);
DISPLAY 0.659574 (-7965 4310);
PAINT MONO (-7965 4310);
DISPLAY INVISIBLE (-7965 4310);
FORCEPROP 1 LAST PATH I3
J 0
(-7900 4250);
DISPLAY 0.872340 (-7900 4250);
PAINT AQUA (-7900 4250);
DISPLAY INVISIBLE (-7900 4250);
FORCEPROP 1 LAST HDL_POWER GND
J 1
(-7950 4175);
DISPLAY 0.872340 (-7950 4175);
PAINT GREEN (-7950 4175);
DISPLAY INVISIBLE (-7950 4175);
FORCEPROP 2 LAST CDS_LIB logical_power
J 0
(-7975 4250);
DISPLAY INVISIBLE (-7975 4250);
FORCEADD OFFPAGE..2
(-4500 1050);
FORCEPROP 2 LAST $XR0 215 
J 0
(-4311 1050);
DISPLAY 0.638298 (-4311 1050);
PAINT MONO (-4311 1050);
FORCEPROP 2 LAST PATH I30
J 0
(-4325 1125);
DISPLAY 1.021277 (-4325 1125);
DISPLAY INVISIBLE (-4325 1125);
FORCEPROP 2 LAST CDS_LIB standard
J 0
(-4500 1050);
DISPLAY INVISIBLE (-4500 1050);
FORCEPROP 1 LAST OFFPAGE TRUE
J 0
(-4175 925);
DISPLAY 0.872340 (-4175 925);
PAINT GREEN (-4175 925);
DISPLAY INVISIBLE (-4175 925);
FORCEPROP 1 LAST COMMENT_BODY TRUE
J 0
(-4545 955);
DISPLAY 0.872340 (-4545 955);
PAINT PEACH (-4545 955);
DISPLAY INVISIBLE (-4545 955);
FORCEADD UNIVERSAL_POWER..1
(-5300 1625);
FORCEPROP 3 LASTPIN (-5300 1575) SIG_NAME P3V3_AUX\g
J 0
(-5290 1585);
DISPLAY 0.659574 (-5290 1585);
PAINT MONO (-5290 1585);
DISPLAY INVISIBLE (-5290 1585);
FORCEPROP 1 LAST HDL_POWER P3V3_AUX
J 1
(-5300 1675);
DISPLAY 0.872340 (-5300 1675);
PAINT GREEN (-5300 1675);
FORCEPROP 1 LAST PATH I31
J 0
(-5250 1650);
DISPLAY 0.872340 (-5250 1650);
PAINT AQUA (-5250 1650);
DISPLAY INVISIBLE (-5250 1650);
FORCEPROP 2 LAST CDS_LIB logical_power
J 0
(-5300 1625);
DISPLAY INVISIBLE (-5300 1625);
FORCEADD Q_RES..2
(-5300 1375);
FORCEPROP 1 LAST PART_NUMBER CS31002FB08
J 0
(-5260 1250);
DISPLAY 0.638298 (-5260 1250);
DISPLAY INVISIBLE (-5260 1250);
FORCEPROP 1 LAST MATERIAL CHIP
J 0
(-5260 1300);
DISPLAY 0.638298 (-5260 1300);
FORCEPROP 1 LAST PACK_TYPE 0402LF
J 0
(-5260 1200);
DISPLAY 0.638298 (-5260 1200);
FORCEPROP 1 LAST TOLERANCE 1%
J 0
(-5255 1400);
DISPLAY 0.638298 (-5255 1400);
FORCEPROP 1 LAST VALUE 10K
J 0
(-5255 1450);
DISPLAY 0.638298 (-5255 1450);
FORCEPROP 1 LAST WATTAGE 1/16W
J 0
(-5260 1350);
DISPLAY 0.638298 (-5260 1350);
FORCEPROP 1 LAST $LOCATION R4719
J 0
(-5255 1500);
DISPLAY 0.978723 (-5255 1500);
FORCEPROP 1 LASTPIN (-5300 1475) $PN 1
J 0
(-5295 1437);
DISPLAY 0.787234 (-5295 1437);
PAINT MONO (-5295 1437);
FORCEPROP 1 LASTPIN (-5300 1275) $PN 2
J 0
(-5295 1285);
DISPLAY 0.787234 (-5295 1285);
PAINT MONO (-5295 1285);
FORCEPROP 1 LAST PATH I32
J 0
(-5250 1550);
DISPLAY 0.978723 (-5250 1550);
PAINT WHITE (-5250 1550);
DISPLAY INVISIBLE (-5250 1550);
FORCEPROP 2 LAST CDS_LIB pure_quanta
J 0
(-5300 1375);
DISPLAY INVISIBLE (-5300 1375);
FORCEPROP 0 LAST CDS_LOCATION R4719
J 0
(-5250 1550);
DISPLAY 1.021277 (-5250 1550);
DISPLAY INVISIBLE (-5250 1550);
FORCEPROP 0 LAST $SEC 1
J 0
(-5250 1550);
DISPLAY 0.680851 (-5250 1550);
PAINT MONO (-5250 1550);
DISPLAY INVISIBLE (-5250 1550);
FORCEPROP 0 LAST CDS_SEC 1
J 0
(-5250 1550);
DISPLAY 1.021277 (-5250 1550);
DISPLAY INVISIBLE (-5250 1550);
FORCEADD Q_RES..1
(-5800 1050);
FORCEPROP 1 LAST PART_NUMBER CS03322FB03
J 0
(-5950 1125);
DISPLAY 0.638298 (-5950 1125);
DISPLAY INVISIBLE (-5950 1125);
FORCEPROP 1 LAST TOLERANCE 1%
J 0
(-5525 1050);
DISPLAY 0.638298 (-5525 1050);
FORCEPROP 1 LAST MATERIAL EMPTY
J 0
(-5450 1050);
DISPLAY 0.638298 (-5450 1050);
PAINT RED (-5450 1050);
FORCEPROP 1 LAST VALUE 33.2
J 2
(-5550 1050);
DISPLAY 0.638298 (-5550 1050);
FORCEPROP 1 LAST $LOCATION R4718
J 0
(-6025 1050);
DISPLAY 0.638298 (-6025 1050);
FORCEPROP 1 LASTPIN (-5900 1050) $PN 1
J 0
(-5888 1062);
DISPLAY 0.787234 (-5888 1062);
PAINT MONO (-5888 1062);
FORCEPROP 1 LASTPIN (-5700 1050) $PN 2
J 0
(-5738 1062);
DISPLAY 0.787234 (-5738 1062);
PAINT MONO (-5738 1062);
FORCEPROP 1 LAST WATTAGE 1/16W
J 2
(-5600 1175);
DISPLAY 0.638298 (-5600 1175);
DISPLAY INVISIBLE (-5600 1175);
FORCEPROP 1 LAST PACK_TYPE 0402LF
J 0
(-5950 1175);
DISPLAY 0.638298 (-5950 1175);
DISPLAY INVISIBLE (-5950 1175);
FORCEPROP 2 LAST CDS_LIB pure_quanta
J 0
(-5800 1050);
DISPLAY INVISIBLE (-5800 1050);
FORCEPROP 1 LAST PATH I33
J 0
(-5850 1200);
DISPLAY 0.978723 (-5850 1200);
PAINT WHITE (-5850 1200);
DISPLAY INVISIBLE (-5850 1200);
FORCEPROP 0 LAST CDS_LOCATION R4718
J 0
(-5450 1100);
DISPLAY 1.021277 (-5450 1100);
DISPLAY INVISIBLE (-5450 1100);
FORCEPROP 0 LAST $SEC 1
J 0
(-5450 1100);
DISPLAY 0.680851 (-5450 1100);
PAINT MONO (-5450 1100);
DISPLAY INVISIBLE (-5450 1100);
FORCEPROP 0 LAST CDS_SEC 1
J 0
(-5450 1100);
DISPLAY 1.021277 (-5450 1100);
DISPLAY INVISIBLE (-5450 1100);
FORCEADD UNIVERSAL_GND..1
(-6700 1200);
FORCEPROP 3 LASTPIN (-6700 1250) SIG_NAME GND\g
J 0
(-6690 1260);
DISPLAY 0.659574 (-6690 1260);
PAINT MONO (-6690 1260);
DISPLAY INVISIBLE (-6690 1260);
FORCEPROP 1 LAST HDL_POWER GND
J 1
(-6675 1125);
DISPLAY 0.872340 (-6675 1125);
PAINT GREEN (-6675 1125);
DISPLAY INVISIBLE (-6675 1125);
FORCEPROP 2 LAST CDS_LIB logical_power
J 0
(-6700 1200);
DISPLAY INVISIBLE (-6700 1200);
FORCEPROP 1 LAST PATH I34
J 0
(-6625 1200);
DISPLAY 0.872340 (-6625 1200);
PAINT AQUA (-6625 1200);
DISPLAY INVISIBLE (-6625 1200);
FORCEADD Q_CAP..1
(-6700 1375);
FORCEPROP 1 LAST PART_NUMBER CH4104K1B00
J 0
(-6650 1325);
DISPLAY 0.319149 (-6650 1325);
DISPLAY INVISIBLE (-6650 1325);
FORCEPROP 1 LAST VALUE 0.1UF
J 0
(-6650 1425);
DISPLAY 0.404255 (-6650 1425);
FORCEPROP 1 LAST VOLTAGE 25V
J 0
(-6650 1400);
DISPLAY 0.404255 (-6650 1400);
FORCEPROP 1 LAST PACK_TYPE 0402
J 0
(-6650 1300);
DISPLAY 0.404255 (-6650 1300);
FORCEPROP 1 LAST TOLERANCE 10%
J 0
(-6650 1375);
DISPLAY 0.404255 (-6650 1375);
FORCEPROP 1 LAST MATERIAL EMPTY
J 0
(-6650 1350);
DISPLAY 0.404255 (-6650 1350);
PAINT RED (-6650 1350);
FORCEPROP 1 LAST $LOCATION C2370
J 0
(-6650 1450);
DISPLAY 0.638298 (-6650 1450);
FORCEPROP 1 LASTPIN (-6700 1475) $PN 1
J 0
(-6690 1455);
DISPLAY 0.787234 (-6690 1455);
PAINT MONO (-6690 1455);
FORCEPROP 1 LASTPIN (-6700 1275) $PN 2
J 0
(-6690 1255);
DISPLAY 0.787234 (-6690 1255);
PAINT MONO (-6690 1255);
FORCEPROP 1 LAST PATH I35
J 0
(-6650 1525);
DISPLAY 0.978723 (-6650 1525);
PAINT WHITE (-6650 1525);
DISPLAY INVISIBLE (-6650 1525);
FORCEPROP 2 LAST CDS_LIB pure_quanta
J 0
(-6700 1375);
DISPLAY INVISIBLE (-6700 1375);
FORCEPROP 0 LAST CDS_LOCATION C2370
J 0
(-6650 1500);
DISPLAY 1.021277 (-6650 1500);
DISPLAY INVISIBLE (-6650 1500);
FORCEPROP 0 LAST $SEC 1
J 0
(-6650 1500);
DISPLAY 0.680851 (-6650 1500);
PAINT MONO (-6650 1500);
DISPLAY INVISIBLE (-6650 1500);
FORCEPROP 0 LAST CDS_SEC 1
J 0
(-6650 1500);
DISPLAY 1.021277 (-6650 1500);
DISPLAY INVISIBLE (-6650 1500);
FORCEADD UNIVERSAL_POWER..1
(-6825 1600);
FORCEPROP 3 LASTPIN (-6825 1550) SIG_NAME P3V3_AUX\g
J 0
(-6815 1560);
DISPLAY 0.659574 (-6815 1560);
PAINT MONO (-6815 1560);
DISPLAY INVISIBLE (-6815 1560);
FORCEPROP 1 LAST HDL_POWER P3V3_AUX
J 1
(-6825 1650);
DISPLAY 0.872340 (-6825 1650);
PAINT GREEN (-6825 1650);
FORCEPROP 2 LAST CDS_LIB logical_power
J 0
(-6825 1600);
DISPLAY INVISIBLE (-6825 1600);
FORCEPROP 1 LAST PATH I36
J 0
(-6775 1625);
DISPLAY 0.872340 (-6775 1625);
PAINT AQUA (-6775 1625);
DISPLAY INVISIBLE (-6775 1625);
FORCEADD 74LVC2G07DW7..1
(-7250 1000);
FORCEPROP 1 LAST PART_NUMBER AL002G07003
J 0
(-7425 1153);
DISPLAY 0.723404 (-7425 1153);
PAINT GREEN (-7425 1153);
DISPLAY INVISIBLE (-7425 1153);
FORCEPROP 2 LAST PART_TYPE SMLF
J 0
(-7406 1394);
DISPLAY 1.021277 (-7406 1394);
FORCEPROP 1 LAST MATERIAL EMPTY
J 0
(-7419 1107);
DISPLAY 0.723404 (-7419 1107);
PAINT RED (-7419 1107);
FORCEPROP 2 LAST VALUE 74LVC2G07DW-7
J 0
(-7556 1219);
DISPLAY 1.021277 (-7556 1219);
FORCEPROP 1 LAST $LOCATION U332
J 0
(-7425 1300);
DISPLAY 0.723404 (-7425 1300);
PAINT GREEN (-7425 1300);
FORCEPROP 0 LASTPIN (-7575 1050) $PN 1
J 2
(-7585 1060);
DISPLAY 0.680851 (-7585 1060);
PAINT MONO (-7585 1060);
FORCEPROP 0 LASTPIN (-6925 1050) $PN 6
J 0
(-6915 1060);
DISPLAY 0.680851 (-6915 1060);
PAINT MONO (-6915 1060);
FORCEPROP 0 LASTPIN (-7575 950) $PN 3
J 2
(-7585 960);
DISPLAY 0.680851 (-7585 960);
PAINT MONO (-7585 960);
FORCEPROP 0 LASTPIN (-6925 950) $PN 4
J 0
(-6915 960);
DISPLAY 0.680851 (-6915 960);
PAINT MONO (-6915 960);
FORCEPROP 0 LASTPIN (-7575 1000) $PN 2
J 2
(-7585 1010);
DISPLAY 0.680851 (-7585 1010);
PAINT MONO (-7585 1010);
FORCEPROP 0 LASTPIN (-6925 1000) $PN 5
J 0
(-6915 1010);
DISPLAY 0.680851 (-6915 1010);
PAINT MONO (-6915 1010);
FORCEPROP 1 LAST PATH I37
J 0
(-7250 1000);
DISPLAY 0.723404 (-7250 1000);
PAINT GREEN (-7250 1000);
DISPLAY INVISIBLE (-7250 1000);
FORCEPROP 2 LAST CDS_LIB pure_quanta
J 0
(-7250 1000);
DISPLAY INVISIBLE (-7250 1000);
FORCEPROP 1 LAST CDS_LMAN_SYM_OUTLINE -175,100,175,-100
J 0
(-7250 1000);
DISPLAY 0.468085 (-7250 1000);
PAINT GREEN (-7250 1000);
DISPLAY INVISIBLE (-7250 1000);
FORCEPROP 1 LAST NEEDS_NO_SIZE TRUE
J 0
(-7250 1000);
DISPLAY 0.723404 (-7250 1000);
PAINT GREEN (-7250 1000);
DISPLAY INVISIBLE (-7250 1000);
FORCEPROP 0 LAST CDS_LOCATION U332
J 0
(-7400 1525);
DISPLAY 1.021277 (-7400 1525);
DISPLAY INVISIBLE (-7400 1525);
FORCEPROP 0 LAST $SEC 1
J 0
(-7400 1525);
DISPLAY 0.680851 (-7400 1525);
PAINT MONO (-7400 1525);
DISPLAY INVISIBLE (-7400 1525);
FORCEPROP 0 LAST CDS_SEC 1
J 0
(-7400 1525);
DISPLAY 1.021277 (-7400 1525);
DISPLAY INVISIBLE (-7400 1525);
FORCEADD UNIVERSAL_GND..1
(-7675 750);
FORCEPROP 3 LASTPIN (-7675 800) SIG_NAME GND\g
J 0
(-7665 810);
DISPLAY 0.659574 (-7665 810);
PAINT MONO (-7665 810);
DISPLAY INVISIBLE (-7665 810);
FORCEPROP 2 LAST CDS_LIB logical_power
J 0
(-7675 750);
DISPLAY INVISIBLE (-7675 750);
FORCEPROP 1 LAST HDL_POWER GND
J 1
(-7650 675);
DISPLAY 0.872340 (-7650 675);
PAINT GREEN (-7650 675);
DISPLAY INVISIBLE (-7650 675);
FORCEPROP 1 LAST PATH I38
J 0
(-7600 750);
DISPLAY 0.872340 (-7600 750);
PAINT AQUA (-7600 750);
DISPLAY INVISIBLE (-7600 750);
FORCEADD UNIVERSAL_POWER..1
(-8850 1625);
FORCEPROP 3 LASTPIN (-8850 1575) SIG_NAME P3V3_AUX\g
J 0
(-8840 1585);
DISPLAY 0.659574 (-8840 1585);
PAINT MONO (-8840 1585);
DISPLAY INVISIBLE (-8840 1585);
FORCEPROP 1 LAST HDL_POWER P3V3_AUX
J 1
(-8850 1675);
DISPLAY 0.872340 (-8850 1675);
PAINT GREEN (-8850 1675);
FORCEPROP 1 LAST PATH I39
J 0
(-8800 1650);
DISPLAY 0.872340 (-8800 1650);
PAINT AQUA (-8800 1650);
DISPLAY INVISIBLE (-8800 1650);
FORCEPROP 2 LAST CDS_LIB logical_power
J 0
(-8850 1625);
DISPLAY INVISIBLE (-8850 1625);
FORCEADD UNIVERSAL_GND..1
(-7775 5275);
FORCEPROP 3 LASTPIN (-7775 5325) SIG_NAME GND\g
J 0
(-7765 5335);
DISPLAY 0.659574 (-7765 5335);
PAINT MONO (-7765 5335);
DISPLAY INVISIBLE (-7765 5335);
FORCEPROP 1 LAST HDL_POWER GND
J 1
(-7750 5200);
DISPLAY 0.872340 (-7750 5200);
PAINT GREEN (-7750 5200);
DISPLAY INVISIBLE (-7750 5200);
FORCEPROP 2 LAST CDS_LIB logical_power
J 0
(-7775 5275);
DISPLAY INVISIBLE (-7775 5275);
FORCEPROP 1 LAST PATH I4
J 0
(-7700 5275);
DISPLAY 0.872340 (-7700 5275);
PAINT AQUA (-7700 5275);
DISPLAY INVISIBLE (-7700 5275);
FORCEADD Q_RES..2
(-8850 1375);
FORCEPROP 1 LAST PART_NUMBER CS28452FB06
J 0
(-8810 1250);
DISPLAY 0.617021 (-8810 1250);
DISPLAY INVISIBLE (-8810 1250);
FORCEPROP 1 LAST PACK_TYPE 0402LF
J 0
(-8810 1200);
DISPLAY 0.617021 (-8810 1200);
FORCEPROP 1 LAST VALUE 8.45K
J 0
(-8805 1450);
DISPLAY 0.617021 (-8805 1450);
FORCEPROP 1 LAST WATTAGE 1/16W
J 0
(-8810 1350);
DISPLAY 0.617021 (-8810 1350);
FORCEPROP 1 LAST TOLERANCE 1%
J 0
(-8805 1400);
DISPLAY 0.617021 (-8805 1400);
FORCEPROP 1 LAST MATERIAL EMPTY
J 0
(-8810 1300);
DISPLAY 0.617021 (-8810 1300);
PAINT RED (-8810 1300);
FORCEPROP 1 LAST $LOCATION R4716
J 0
(-8805 1500);
DISPLAY 0.617021 (-8805 1500);
FORCEPROP 1 LASTPIN (-8850 1475) $PN 1
J 0
(-8845 1437);
DISPLAY 0.787234 (-8845 1437);
PAINT MONO (-8845 1437);
FORCEPROP 1 LASTPIN (-8850 1275) $PN 2
J 0
(-8845 1285);
DISPLAY 0.787234 (-8845 1285);
PAINT MONO (-8845 1285);
FORCEPROP 1 LAST PATH I40
J 0
(-8800 1550);
DISPLAY 0.978723 (-8800 1550);
PAINT WHITE (-8800 1550);
DISPLAY INVISIBLE (-8800 1550);
FORCEPROP 2 LAST CDS_LIB pure_quanta
J 0
(-8850 1375);
DISPLAY INVISIBLE (-8850 1375);
FORCEPROP 0 LAST CDS_LOCATION R4716
J 0
(-8800 1550);
DISPLAY 1.021277 (-8800 1550);
DISPLAY INVISIBLE (-8800 1550);
FORCEPROP 0 LAST $SEC 1
J 0
(-8800 1550);
DISPLAY 0.680851 (-8800 1550);
PAINT MONO (-8800 1550);
DISPLAY INVISIBLE (-8800 1550);
FORCEPROP 0 LAST CDS_SEC 1
J 0
(-8800 1550);
DISPLAY 1.021277 (-8800 1550);
DISPLAY INVISIBLE (-8800 1550);
FORCEADD Q_RES..1
(-8650 1050);
FORCEPROP 1 LAST PART_NUMBER CS00002JB13
J 0
(-8700 1100);
DISPLAY 0.404255 (-8700 1100);
DISPLAY INVISIBLE (-8700 1100);
FORCEPROP 1 LAST TOLERANCE 5%
J 0
(-8475 1050);
DISPLAY 0.510638 (-8475 1050);
FORCEPROP 1 LAST VALUE 0
J 2
(-8500 1050);
DISPLAY 0.510638 (-8500 1050);
FORCEPROP 1 LAST MATERIAL EMPTY
J 0
(-8400 1050);
DISPLAY 0.510638 (-8400 1050);
PAINT RED (-8400 1050);
FORCEPROP 1 LAST $LOCATION R4717
J 0
(-8800 1075);
DISPLAY 0.978723 (-8800 1075);
FORCEPROP 1 LASTPIN (-8750 1050) $PN 1
J 0
(-8738 1062);
DISPLAY 0.787234 (-8738 1062);
PAINT MONO (-8738 1062);
FORCEPROP 1 LASTPIN (-8550 1050) $PN 2
J 0
(-8588 1062);
DISPLAY 0.787234 (-8588 1062);
PAINT MONO (-8588 1062);
FORCEPROP 1 LAST PATH I41
J 0
(-8700 1200);
DISPLAY 0.978723 (-8700 1200);
PAINT WHITE (-8700 1200);
DISPLAY INVISIBLE (-8700 1200);
FORCEPROP 1 LAST WATTAGE 1/16W
J 2
(-8475 1125);
DISPLAY 0.404255 (-8475 1125);
DISPLAY INVISIBLE (-8475 1125);
FORCEPROP 1 LAST PACK_TYPE 0402LF
J 0
(-8400 1050);
DISPLAY 0.510638 (-8400 1050);
DISPLAY INVISIBLE (-8400 1050);
FORCEPROP 2 LAST CDS_LIB pure_quanta
J 0
(-8650 1050);
DISPLAY INVISIBLE (-8650 1050);
FORCEPROP 0 LAST CDS_LOCATION R4717
J 0
(-8800 1125);
DISPLAY 1.021277 (-8800 1125);
DISPLAY INVISIBLE (-8800 1125);
FORCEPROP 0 LAST $SEC 1
J 0
(-8800 1125);
DISPLAY 0.680851 (-8800 1125);
PAINT MONO (-8800 1125);
DISPLAY INVISIBLE (-8800 1125);
FORCEPROP 0 LAST CDS_SEC 1
J 0
(-8800 1125);
DISPLAY 1.021277 (-8800 1125);
DISPLAY INVISIBLE (-8800 1125);
FORCEADD Q_CAP..1
R 2
(-8825 850);
FORCEPROP 1 LAST PART_NUMBER CH5104KEB02
J 0
(-8775 650);
DISPLAY 0.510638 (-8775 650);
DISPLAY INVISIBLE (-8775 650);
FORCEPROP 1 LAST TOLERANCE 10%
J 0
(-8775 750);
DISPLAY 0.510638 (-8775 750);
FORCEPROP 1 LAST VALUE 1UF
J 0
(-8775 850);
DISPLAY 0.510638 (-8775 850);
FORCEPROP 1 LAST VOLTAGE 25V
J 0
(-8775 800);
DISPLAY 0.510638 (-8775 800);
FORCEPROP 1 LAST PACK_TYPE C0402
J 0
(-8775 600);
DISPLAY 0.510638 (-8775 600);
FORCEPROP 1 LAST MATERIAL EMPTY
J 0
(-8775 700);
DISPLAY 0.510638 (-8775 700);
PAINT RED (-8775 700);
FORCEPROP 1 LAST $LOCATION C2369
J 0
(-8775 900);
DISPLAY 0.978723 (-8775 900);
FORCEPROP 1 LASTPIN (-8825 950) $PN 1
J 2
(-8835 930);
DISPLAY 0.787234 (-8835 930);
PAINT MONO (-8835 930);
FORCEPROP 1 LASTPIN (-8825 750) $PN 2
J 2
(-8835 730);
DISPLAY 0.787234 (-8835 730);
PAINT MONO (-8835 730);
FORCEPROP 1 LAST PATH I42
J 2
(-8875 1000);
DISPLAY 0.978723 (-8875 1000);
PAINT WHITE (-8875 1000);
DISPLAY INVISIBLE (-8875 1000);
FORCEPROP 2 LAST CDS_LIB pure_quanta
J 0
(-8825 850);
DISPLAY INVISIBLE (-8825 850);
FORCEPROP 0 LAST CDS_LOCATION C2369
J 0
(-8775 950);
DISPLAY 1.021277 (-8775 950);
DISPLAY INVISIBLE (-8775 950);
FORCEPROP 0 LAST $SEC 1
J 0
(-8775 950);
DISPLAY 0.680851 (-8775 950);
PAINT MONO (-8775 950);
DISPLAY INVISIBLE (-8775 950);
FORCEPROP 0 LAST CDS_SEC 1
J 0
(-8775 950);
DISPLAY 1.021277 (-8775 950);
DISPLAY INVISIBLE (-8775 950);
FORCEADD UNIVERSAL_GND..1
(-8825 650);
FORCEPROP 3 LASTPIN (-8825 700) SIG_NAME GND\g
J 0
(-8815 710);
DISPLAY 0.659574 (-8815 710);
PAINT MONO (-8815 710);
DISPLAY INVISIBLE (-8815 710);
FORCEPROP 1 LAST PATH I43
J 0
(-8750 650);
DISPLAY 0.872340 (-8750 650);
PAINT AQUA (-8750 650);
DISPLAY INVISIBLE (-8750 650);
FORCEPROP 1 LAST HDL_POWER GND
J 1
(-8800 575);
DISPLAY 0.872340 (-8800 575);
PAINT GREEN (-8800 575);
DISPLAY INVISIBLE (-8800 575);
FORCEPROP 2 LAST CDS_LIB logical_power
J 0
(-8825 650);
DISPLAY INVISIBLE (-8825 650);
FORCEADD OFFPAGE..1
(-9500 1050);
FORCEPROP 2 LAST $XR1 245 
J 0
(-9872 1050);
DISPLAY 0.638298 (-9872 1050);
PAINT MONO (-9872 1050);
FORCEPROP 2 LAST $XR0 240 
J 0
(-9752 1050);
DISPLAY 0.638298 (-9752 1050);
PAINT MONO (-9752 1050);
FORCEPROP 2 LAST PATH I44
J 0
(-9450 1125);
DISPLAY 1.021277 (-9450 1125);
DISPLAY INVISIBLE (-9450 1125);
FORCEPROP 1 LAST OFFPAGE TRUE
J 0
(-9175 925);
DISPLAY 0.872340 (-9175 925);
DISPLAY INVISIBLE (-9175 925);
FORCEPROP 1 LAST COMMENT_BODY TRUE
J 0
(-9375 950);
DISPLAY 1.170213 (-9375 950);
PAINT GREEN (-9375 950);
DISPLAY INVISIBLE (-9375 950);
FORCEPROP 2 LAST CDS_LIB standard
J 0
(-9500 1050);
DISPLAY INVISIBLE (-9500 1050);
FORCEADD Q_CAP..1
(-7775 5475);
FORCEPROP 1 LAST PART_NUMBER CH4104K1B00
J 0
(-7725 5325);
DISPLAY 0.510638 (-7725 5325);
DISPLAY INVISIBLE (-7725 5325);
FORCEPROP 1 LAST PACK_TYPE 0402
J 0
(-7725 5275);
DISPLAY 0.510638 (-7725 5275);
FORCEPROP 1 LAST VALUE 0.1UF
J 0
(-7725 5525);
DISPLAY 0.510638 (-7725 5525);
FORCEPROP 1 LAST VOLTAGE 25V
J 0
(-7725 5475);
DISPLAY 0.510638 (-7725 5475);
FORCEPROP 1 LAST MATERIAL X7R
J 0
(-7725 5375);
DISPLAY 0.510638 (-7725 5375);
FORCEPROP 1 LAST TOLERANCE 10%
J 0
(-7725 5425);
DISPLAY 0.510638 (-7725 5425);
FORCEPROP 1 LAST $LOCATION C1619
J 0
(-7725 5575);
DISPLAY 0.978723 (-7725 5575);
FORCEPROP 1 LASTPIN (-7775 5575) $PN 1
J 0
(-7765 5555);
DISPLAY 0.787234 (-7765 5555);
PAINT MONO (-7765 5555);
FORCEPROP 1 LASTPIN (-7775 5375) $PN 2
J 0
(-7765 5355);
DISPLAY 0.787234 (-7765 5355);
PAINT MONO (-7765 5355);
FORCEPROP 2 LAST CDS_LIB pure_quanta
J 2
(-7775 5475);
DISPLAY INVISIBLE (-7775 5475);
FORCEPROP 1 LAST PATH I5
J 0
(-7725 5625);
DISPLAY 0.978723 (-7725 5625);
PAINT WHITE (-7725 5625);
DISPLAY INVISIBLE (-7725 5625);
FORCEPROP 0 LAST CDS_LOCATION C1619
J 2
(-7725 5625);
DISPLAY 1.021277 (-7725 5625);
DISPLAY INVISIBLE (-7725 5625);
FORCEPROP 0 LAST $SEC 1
J 2
(-7725 5625);
DISPLAY 0.680851 (-7725 5625);
PAINT MONO (-7725 5625);
DISPLAY INVISIBLE (-7725 5625);
FORCEPROP 0 LAST CDS_SEC 1
J 2
(-7725 5625);
DISPLAY 1.021277 (-7725 5625);
DISPLAY INVISIBLE (-7725 5625);
FORCEADD UNIVERSAL_POWER..1
(-7775 5750);
FORCEPROP 3 LASTPIN (-7775 5700) SIG_NAME P3V3_AUX\g
J 0
(-7765 5710);
DISPLAY 0.659574 (-7765 5710);
PAINT MONO (-7765 5710);
DISPLAY INVISIBLE (-7765 5710);
FORCEPROP 1 LAST HDL_POWER P3V3_AUX
J 1
(-7775 5800);
DISPLAY 0.872340 (-7775 5800);
PAINT GREEN (-7775 5800);
FORCEPROP 2 LAST CDS_LIB logical_power
J 0
(-7775 5750);
DISPLAY INVISIBLE (-7775 5750);
FORCEPROP 1 LAST PATH I6
J 0
(-7725 5775);
DISPLAY 0.872340 (-7725 5775);
PAINT AQUA (-7725 5775);
DISPLAY INVISIBLE (-7725 5775);
FORCEADD Q_RES..2
R 2
(-6225 5250);
FORCEPROP 1 LAST PART_NUMBER CS24702JB10
J 2
(-6265 5125);
DISPLAY 0.510638 (-6265 5125);
DISPLAY INVISIBLE (-6265 5125);
FORCEPROP 1 LAST PACK_TYPE 0402LF
J 2
(-6265 5075);
DISPLAY 0.510638 (-6265 5075);
FORCEPROP 1 LAST VALUE 4.7K
J 2
(-6270 5325);
DISPLAY 0.510638 (-6270 5325);
FORCEPROP 1 LAST MATERIAL EMPTY
J 2
(-6265 5175);
DISPLAY 0.510638 (-6265 5175);
FORCEPROP 1 LAST WATTAGE 1/16W
J 2
(-6265 5225);
DISPLAY 0.510638 (-6265 5225);
FORCEPROP 1 LAST TOLERANCE 5%
J 2
(-6270 5275);
DISPLAY 0.510638 (-6270 5275);
FORCEPROP 1 LAST $LOCATION R2355
J 2
(-6270 5375);
DISPLAY 0.808511 (-6270 5375);
FORCEPROP 1 LASTPIN (-6225 5350) $PN 1
J 2
(-6230 5312);
DISPLAY 0.787234 (-6230 5312);
PAINT MONO (-6230 5312);
FORCEPROP 1 LASTPIN (-6225 5150) $PN 2
J 2
(-6230 5160);
DISPLAY 0.787234 (-6230 5160);
PAINT MONO (-6230 5160);
FORCEPROP 2 LAST CDS_LIB pure_quanta
J 2
(-6225 5250);
DISPLAY INVISIBLE (-6225 5250);
FORCEPROP 1 LAST PATH I7
J 2
(-6275 5425);
DISPLAY 0.978723 (-6275 5425);
PAINT WHITE (-6275 5425);
DISPLAY INVISIBLE (-6275 5425);
FORCEPROP 0 LAST CDS_LOCATION R2355
J 2
(-6275 5400);
DISPLAY 1.021277 (-6275 5400);
DISPLAY INVISIBLE (-6275 5400);
FORCEPROP 0 LAST $SEC 1
J 2
(-6275 5400);
DISPLAY 0.680851 (-6275 5400);
PAINT MONO (-6275 5400);
DISPLAY INVISIBLE (-6275 5400);
FORCEPROP 0 LAST CDS_SEC 1
J 2
(-6275 5400);
DISPLAY 1.021277 (-6275 5400);
DISPLAY INVISIBLE (-6275 5400);
FORCEADD UNIVERSAL_POWER..1
(-6225 5450);
FORCEPROP 3 LASTPIN (-6225 5400) SIG_NAME P3V3_AUX\g
J 0
(-6215 5410);
DISPLAY 0.659574 (-6215 5410);
PAINT MONO (-6215 5410);
DISPLAY INVISIBLE (-6215 5410);
FORCEPROP 1 LAST HDL_POWER P3V3_AUX
J 1
(-6225 5500);
DISPLAY 0.872340 (-6225 5500);
PAINT GREEN (-6225 5500);
FORCEPROP 2 LAST CDS_LIB logical_power
J 0
(-6225 5450);
DISPLAY INVISIBLE (-6225 5450);
FORCEPROP 1 LAST PATH I8
J 0
(-6175 5475);
DISPLAY 0.872340 (-6175 5475);
PAINT AQUA (-6175 5475);
DISPLAY INVISIBLE (-6175 5475);
FORCEADD QUANTA_TITLE_BLOCK_C..1
(-2725 -150);
FORCEPROP 0 LAST CDS_CON_LAST_MODIFIED Fri Aug 25 14:03:45 2023
J 0
(-4610 -135);
PAINT MONO (-4610 -135);
DISPLAY INVISIBLE (-4610 -135);
FORCEPROP 1 LAST CUSTOM_TXT_CDS <CON_LAST_MODIFIED>
J 0
(-4610 -135);
DISPLAY 0.978723 (-4610 -135);
FORCEPROP 2 LAST CUSTOM_TXT_CDS <XR_PAGE_TITLE>
J 0
(-10615 5100);
DISPLAY 0.638298 (-10615 5100);
PAINT PINK (-10615 5100);
DISPLAY INVISIBLE (-10615 5100);
FORCEPROP 1 LAST CUSTOM_TXT_CDS <NAME_2>
J 0
(-5900 -100);
FORCEPROP 1 LAST CUSTOM_TXT_CDS <NAME_1>
J 0
(-5900 25);
FORCEPROP 1 LAST CUSTOM_TXT_CDS <Q_NUMBER>
J 0
(-4128 -47);
DISPLAY 1.212766 (-4128 -47);
FORCEPROP 1 LAST CUSTOM_TXT_CDS <Q_PROJ>
J 0
(-5107 -48);
DISPLAY 1.212766 (-5107 -48);
FORCEPROP 1 LAST CUSTOM_TXT_CDS <Q_REV>
J 0
(-2909 -47);
DISPLAY 1.212766 (-2909 -47);
FORCEPROP 1 LAST CUSTOM_TXT_CDS <CON_PAGE_NUM> OF <CON_TOTAL_PAGES>
J 0
(-3171 -132);
DISPLAY 0.978723 (-3171 -132);
FORCEPROP 1 LAST Q_TITLE MAIN FPGA / PFR - ISOLATOR
J 0
(-11991 -124);
DISPLAY 2.446809 (-11991 -124);
PAINT GREEN (-11991 -124);
FORCEPROP 1 LAST Q_DEPT 
J 1
(-6488 -101);
DISPLAY 1.957447 (-6488 -101);
PAINT GREEN (-6488 -101);
FORCEPROP 2 LAST CDS_XR_PAGE_TITLE CR-224 : @S9S_MB_2U_LIB.S9S_MB_2U(SCH_1):PAGE224
J 0
(-10615 5100);
DISPLAY 0.638298 (-10615 5100);
PAINT PINK (-10615 5100);
DISPLAY INVISIBLE (-10615 5100);
FORCEPROP 1 LAST CDS_LMAN_SYM_OUTLINE -9475,6775,100,-125
J 0
(-2725 -150);
DISPLAY 0.468085 (-2725 -150);
PAINT GREEN (-2725 -150);
DISPLAY INVISIBLE (-2725 -150);
FORCEPROP 2 LAST CDS_LIB pure_quanta
J 0
(-2725 -150);
PAINT MONO (-2725 -150);
DISPLAY INVISIBLE (-2725 -150);
FORCEPROP 1 LAST COMMENT_BODY TRUE
J 0
(-2713 -163);
DISPLAY 0.978723 (-2713 -163);
PAINT GREEN (-2713 -163);
DISPLAY INVISIBLE (-2713 -163);
FORCEPROP 2 LAST PAGE_BORDER TRUE
J 0
(-10615 5100);
DISPLAY 0.638298 (-10615 5100);
PAINT PINK (-10615 5100);
DISPLAY INVISIBLE (-10615 5100);
FORCEADD DNS..2
(-5775 1050);
PAINT RED (-5775 1050);
FORCEPROP 2 LAST CDS_LIB mstr_misc
J 0
(-5775 1050);
DISPLAY INVISIBLE (-5775 1050);
FORCEPROP 1 LAST COMMENT_BODY TRUE
R 1
J 0
(-5700 825);
DISPLAY 0.872340 (-5700 825);
PAINT GREEN (-5700 825);
DISPLAY INVISIBLE (-5700 825);
FORCEADD DNS..2
(-8825 825);
PAINT RED (-8825 825);
FORCEPROP 1 LAST COMMENT_BODY TRUE
R 1
J 0
(-8750 600);
DISPLAY 0.872340 (-8750 600);
PAINT GREEN (-8750 600);
DISPLAY INVISIBLE (-8750 600);
FORCEPROP 2 LAST CDS_LIB mstr_misc
J 0
(-8825 825);
DISPLAY INVISIBLE (-8825 825);
FORCEADD DNS..2
(-8625 1050);
PAINT RED (-8625 1050);
FORCEPROP 1 LAST COMMENT_BODY TRUE
R 1
J 0
(-8550 825);
DISPLAY 0.872340 (-8550 825);
PAINT GREEN (-8550 825);
DISPLAY INVISIBLE (-8550 825);
FORCEPROP 2 LAST CDS_LIB mstr_misc
J 0
(-8625 1050);
DISPLAY INVISIBLE (-8625 1050);
FORCEADD DNS..2
(-8825 1375);
PAINT RED (-8825 1375);
FORCEPROP 1 LAST COMMENT_BODY TRUE
R 1
J 0
(-8750 1150);
DISPLAY 0.872340 (-8750 1150);
PAINT GREEN (-8750 1150);
DISPLAY INVISIBLE (-8750 1150);
FORCEPROP 2 LAST CDS_LIB mstr_misc
J 0
(-8825 1375);
DISPLAY INVISIBLE (-8825 1375);
FORCEADD DNS..2
(-6675 1375);
PAINT RED (-6675 1375);
FORCEPROP 1 LAST COMMENT_BODY TRUE
R 1
J 0
(-6600 1150);
DISPLAY 0.872340 (-6600 1150);
PAINT GREEN (-6600 1150);
DISPLAY INVISIBLE (-6600 1150);
FORCEPROP 2 LAST CDS_LIB mstr_misc
J 0
(-6675 1375);
DISPLAY INVISIBLE (-6675 1375);
FORCEADD DNS..2
(-7275 950);
PAINT RED (-7275 950);
FORCEPROP 1 LAST COMMENT_BODY TRUE
R 1
J 0
(-7200 725);
DISPLAY 0.872340 (-7200 725);
PAINT GREEN (-7200 725);
DISPLAY INVISIBLE (-7200 725);
FORCEPROP 2 LAST CDS_LIB mstr_misc
J 0
(-7275 950);
DISPLAY INVISIBLE (-7275 950);
FORCEADD DNS..2
(-6225 5225);
PAINT RED (-6225 5225);
FORCEPROP 2 LAST CDS_LIB mstr_misc
J 0
(-6225 5225);
DISPLAY INVISIBLE (-6225 5225);
FORCEPROP 1 LAST COMMENT_BODY TRUE
R 1
J 0
(-6150 5000);
DISPLAY 0.872340 (-6150 5000);
PAINT GREEN (-6150 5000);
DISPLAY INVISIBLE (-6150 5000);
FORCEADD CAD_NOTE..1
(-6775 4500);
FORCEPROP 0 LAST S1 PLACE U150 NEAR FRONT SIDE OF MB
J 0
(-6925 4375);
DISPLAY 1.021277 (-6925 4375);
PAINT SKYBLUE (-6925 4375);
FORCEPROP 1 LAST COMMENT_BODY TRUE
J 0
(-6750 4600);
DISPLAY 0.978723 (-6750 4600);
DISPLAY INVISIBLE (-6750 4600);
FORCEPROP 2 LAST CDS_LIB logical_power
J 0
(-6775 4500);
DISPLAY INVISIBLE (-6775 4500);
WIRE 16 -1 (-8850 1475)(-8850 1575);
WIRE 16 -1 (-5300 1475)(-5300 1575);
WIRE 16 -1 (-8275 3125)(-8275 3050);
WIRE 16 -1 (-6825 1550)(-6825 1500);
WIRE 16 -1 (-7125 3250)(-7125 3175);
WIRE 16 -1 (-7775 5625)(-7775 5700);
WIRE 16 -1 (-7775 5625)(-7975 5625);
FORCEPROP 0 LAST VOLTAGE 3.3
J 0
(-7850 5625);
DISPLAY INVISIBLE (-7850 5625);
WIRE 16 -1 (-7775 5575)(-7775 5625);
WIRE 16 -1 (-6225 5400)(-6225 5350);
WIRE 16 -1 (-8825 750)(-8825 700);
WIRE 16 -1 (-6700 1275)(-6700 1250);
WIRE 16 -1 (-7675 950)(-7675 800);
WIRE 16 -1 (-7675 1000)(-7675 950);
WIRE 16 -1 (-7575 950)(-7675 950);
WIRE 16 -1 (-8275 2150)(-8275 2025);
WIRE 16 -1 (-7125 2450)(-7125 2325);
WIRE 16 -1 (-7975 4400)(-7975 4300);
WIRE 16 -1 (-7775 5375)(-7775 5325);
WIRE 16 -1 (-8850 1050)(-9450 1050);
FORCEPROP 0 LAST CDS_PHYS_NET_NAME TP_SPI_TPM_CLK
J 0
(-9360 1084);
PAINT MONO (-9360 1084);
DISPLAY INVISIBLE (-9360 1084);
FORCEPROP 2 LAST SIG_NAME FM_AC_PWR_BTN_R_N
J 0
(-9435 1060);
DISPLAY 0.638298 (-9435 1060);
PAINT RED (-9435 1060);
WIRE 16 -1 (-8850 1275)(-8850 1050);
WIRE 16 -1 (-8825 1050)(-8825 950);
WIRE 16 -1 (-8825 1050)(-8850 1050);
WIRE 16 -1 (-8750 1050)(-8825 1050);
WIRE 16 2175 (-9925 3400)(-3775 3400);
WIRE 16 2175 (-3775 3400)(-3775 1950);
WIRE 16 2175 (-9925 3400)(-9925 1950);
WIRE 16 2175 (-9925 1950)(-3775 1950);
WIRE 16 2175 (-9925 375)(-3775 375);
WIRE 16 2175 (-3775 1825)(-3775 375);
WIRE 16 2175 (-9925 1825)(-9925 375);
WIRE 16 2175 (-9925 1825)(-3775 1825);
WIRE 16 -1 (-9450 2300)(-8525 2300);
FORCEPROP 2 LAST SIG_NAME PWRGD_PS_PWROK_PLD
J 0
(-9335 2310);
DISPLAY 0.851064 (-9335 2310);
PAINT WHITE (-9335 2310);
WIRE 16 -1 (-7575 1000)(-7675 1000);
WIRE 16 -1 (-5300 1050)(-5700 1050);
FORCEPROP 0 LAST CDS_PHYS_NET_NAME TP_SPI_TPM_CLK
J 0
(-5610 1084);
PAINT MONO (-5610 1084);
DISPLAY INVISIBLE (-5610 1084);
WIRE 16 -1 (-5300 1275)(-5300 1050);
WIRE 16 -1 (-4550 1050)(-5300 1050);
FORCEPROP 2 LAST SIG_NAME FM_AC_PWR_BTN_PLD_ISO_N
J 0
(-5260 1060);
DISPLAY 0.638298 (-5260 1060);
PAINT RED (-5260 1060);
WIRE 16 -1 (-5900 1050)(-6925 1050);
FORCEPROP 0 LAST CDS_PHYS_NET_NAME TP_SPI_TPM_CLK
J 0
(-6835 1084);
PAINT MONO (-6835 1084);
DISPLAY INVISIBLE (-6835 1084);
FORCEPROP 2 LAST SIG_NAME FM_AC_PWR_BTN_PLD_ISO_R_N
J 0
(-6810 1060);
DISPLAY 0.638298 (-6810 1060);
PAINT RED (-6810 1060);
WIRE 16 -1 (-5925 950)(-6925 950);
FORCEPROP 0 LAST CDS_PHYS_NET_NAME TP_SPI_TPM_CLK
J 0
(-6835 984);
PAINT MONO (-6835 984);
DISPLAY INVISIBLE (-6835 984);
FORCEPROP 2 LAST SIG_NAME NC_UXX_2Y
J 0
(-6560 960);
DISPLAY 0.638298 (-6560 960);
PAINT RED (-6560 960);
WIRE 16 -1 (-6825 1000)(-6925 1000);
WIRE 16 -1 (-6825 1500)(-6825 1000);
WIRE 16 -1 (-6825 1500)(-6700 1500);
WIRE 16 -1 (-6700 1500)(-6700 1475);
WIRE 16 -1 (-7575 1050)(-8550 1050);
FORCEPROP 0 LAST CDS_PHYS_NET_NAME TP_SPI_TPM_CLK
J 0
(-8460 1084);
PAINT MONO (-8460 1084);
DISPLAY INVISIBLE (-8460 1084);
FORCEPROP 2 LAST SIG_NAME FM_AC_PWR_BTN_PLD_N
J 0
(-8235 1060);
DISPLAY 0.638298 (-8235 1060);
PAINT RED (-8235 1060);
WIRE 16 -1 (-8275 2850)(-8275 2600);
WIRE 16 -1 (-7375 2600)(-8275 2600);
FORCEPROP 2 LAST SIG_NAME PWRGD_PS_PWROK_PLD_N
J 0
(-8210 2610);
DISPLAY 0.808511 (-8210 2610);
WIRE 16 -1 (-8275 2550)(-8275 2600);
WIRE 16 -1 (-7625 4950)(-6225 4950);
FORCEPROP 2 LAST SIG_NAME FM_PS_EN_PLD_BUF1
J 0
(-7260 4960);
DISPLAY 0.553191 (-7260 4960);
PAINT WHITE (-7260 4960);
WIRE 16 -1 (-5775 4950)(-6225 4950);
WIRE 16 -1 (-6225 5150)(-6225 4950);
WIRE 16 -1 (-6400 4700)(-7625 4700);
FORCEPROP 2 LAST SIG_NAME NC_U150_B1
J 0
(-7285 4710);
DISPLAY 0.553191 (-7285 4710);
PAINT WHITE (-7285 4710);
WIRE 16 -1 (-4250 2900)(-5750 2900);
FORCEPROP 2 LAST SIG_NAME PWRGD_PS_PWROK_PLD_ISO_R
J 0
(-5335 2910);
DISPLAY 0.851064 (-5335 2910);
PAINT WHITE (-5335 2910);
WIRE 16 -1 (-8375 4950)(-9200 4950);
FORCEPROP 2 LAST SIG_NAME FM_PS_EN_PLD_R
J 0
(-9085 4960);
DISPLAY 0.553191 (-9085 4960);
PAINT WHITE (-9085 4960);
WIRE 16 -1 (-8375 4700)(-9200 4700);
FORCEPROP 2 LAST SIG_NAME NC_U150_A1
J 0
(-9085 4710);
DISPLAY 0.553191 (-9085 4710);
PAINT WHITE (-9085 4710);
WIRE 16 -1 (-7125 2900)(-7125 2850);
WIRE 16 -1 (-7125 2975)(-7125 2900);
WIRE 16 -1 (-5950 2900)(-7125 2900);
FORCEPROP 2 LAST SIG_NAME PWRGD_PS_PWROK_PLD_ISO
J 0
(-7060 2910);
DISPLAY 0.808511 (-7060 2910);
WIRE 16 -1 (-7975 5250)(-7975 5625);
DOT 1 (-5300 1050);
DOT 1 (-8850 1050);
DOT 1 (-8825 1050);
DOT 1 (-7675 950);
DOT 1 (-6825 1500);
DOT 1 (-8275 2600);
DOT 1 (-7125 2900);
DOT 1 (-7775 5625);
DOT 1 (-6225 4950);
FORCENOTE
20220215 ADD ISOLATER
(-8900 3425) 0;
DISPLAY LEFT (-8900 3425);
DISPLAY 1.063830 (-8900 3425);
PAINT WHITE (-8900 3425);
FORCENOTE
20220801 ADD ISOLATER
(-8800 1850) 0;
DISPLAY LEFT (-8800 1850);
DISPLAY 1.063830 (-8800 1850);
PAINT WHITE (-8800 1850);
QUIT
